FILE_TYPE = CONNECTIVITY;
{Allegro Design Entry HDL 17.2-2016 S081 (4005846) 1/11/2022}
"PAGE_NUMBER" = 239;
0"NC";
1"P3V3_AUX\g";
2"P3V3_AUX\g";
3"P3V3_AUX\g";
4"P3V3_AUX\g";
5"P5V\g";
6"P12V_AUX\g";
7"P3V3\g";
8"GND\g";
9"GND\g";
10"GND\g";
11"GND\g";
12"GND\g";
13"GND\g";
14"GND\g";
15"GND\g";
16"GND\g";
17"GND\g";
18"GND\g";
19"GND\g";
20"GND\g";
21"GND\g";
22"GND\g";
23"GND\g";
24"GND\g";
25"GND\g";
26"GND\g";
27"GND\g";
28"GND\g";
29"GND\g";
30"GND\g";
31"GND\g";
32"GND\g";
33"GND\g";
34"GND\g";
35"GND\g";
36"GND\g";
37"GND\g";
38"GND\g";
39"GND\g";
40"P3V3_ADC128_VCC";
41"ADC128_A0"CDS_PHYS_NET_NAME"SMB_SEN_3V3AUX_SCL";
42"SMB_SEN_TIC_3V3AUX_SDA"CDS_PHYS_NET_NAME"SMB_TMP75_21_3V3AUX_SDA_R";
43"P3V3_PDB_AUX_ADC";
44"P12V_OCP_SFF_ISENSE_MPS_TIC"CDS_PHYS_NET_NAME"P12V_OCP_SFF_ISENSE_MPS_TIC";
45"P12V_OCP_SFF_ISENSE_MAM_TIC"CDS_PHYS_NET_NAME"P12V_OCP_SFF_ISENSE_MAM_TIC";
46"P3V3_AUX_ADC_MAM"CDS_PHYS_NET_NAME"P3V3_AUX_SENSE";
47"P12V_OCP_V3_2_ISENSE_MAM_MAM"CDS_PHYS_NET_NAME"P12V_OCP_V3_2_ISENSE_MAM_MAM";
48"P12V_OCP_SFF_ISENSE_TIC"CDS_PHYS_NET_NAME"P12V_OCP_SFF_ISENSE_TIC";
49"P12V_OCP_V3_2_ISENSE_MAM"CDS_PHYS_NET_NAME"P12V_OCP_V3_2_ISENSE_MAM";
50"P12V_OCP_V3_2_ISENSE_TIC"CDS_PHYS_NET_NAME"P12V_OCP_V3_2_ISENSE_TIC";
51"P12V_E1S_0_ISENSE_MAM"CDS_PHYS_NET_NAME"P12V_OCP_V3_2_ISENSE_MAM";
52"P12V_E1S_0_ISENSE_MPS_MAM"CDS_PHYS_NET_NAME"P12V_OCP_V3_2_ISENSE_MPS_MAM";
53"P12V_OCP_V3_2_ISENSE_MPS_MAM"CDS_PHYS_NET_NAME"P12V_OCP_V3_2_ISENSE_MPS_MAM";
54"P12V_AUX_ADC_MAM"CDS_PHYS_NET_NAME"SMB_SEN_3V3AUX_SCL";
55"P12V_E1S_0_ISENSE_MAM_MAM"CDS_PHYS_NET_NAME"P12V_OCP_V3_2_ISENSE_MAM_MAM";
56"P12V_OCP_SFF_ISENSE_MAM"CDS_PHYS_NET_NAME"SMB_SEN_3V3AUX_SCL";
57"SMB_SEN_MAM_3V3AUX_SDA"CDS_PHYS_NET_NAME"SMB_TMP75_21_3V3AUX_SDA_R";
58"ADC128_VREF"CDS_PHYS_NET_NAME"SMB_TMP75_21_3V3AUX_SDA_R";
59"P5V_ADC_TIC"CDS_PHYS_NET_NAME"P5V_ADC_TIC";
60"P3V3_ADC_TIC"CDS_PHYS_NET_NAME"P3V3_ADC_TIC";
61"P12V_E1S_0_ISENSE_TIC"CDS_PHYS_NET_NAME"P3V3_PDB_AUX_ADC_TIC";
62"P12V_OCP_V3_2_ISENSE_MAM"CDS_PHYS_NET_NAME"P12V_AUX_ADC_MAM";
63"P5V_ADC_MAM"CDS_PHYS_NET_NAME"P5V_ADC_MAM";
64"SMB_VR_3V3AUX_SCL_R1"CDS_PHYS_NET_NAME"SMB_TEMP_3V3AUX_SCL";
65"P12V_AUX_ADC_TIC"CDS_PHYS_NET_NAME"P3V3_AUX_SENSE";
66"P12V_AUX_ADC_MAM"CDS_PHYS_NET_NAME"P3V3_AUX_SENSE";
67"P12V_E1S_0_ISENSE_TIC"CDS_PHYS_NET_NAME"P12V_OCP_V3_2_ISENSE_TIC";
68"P12V_E1S_0_ISENSE_MPS_TIC"CDS_PHYS_NET_NAME"P12V_OCP_V3_2_ISENSE_MPS_MAM";
69"P12V_E1S_0_ISENSE_MAM_TIC"CDS_PHYS_NET_NAME"P12V_OCP_V3_2_ISENSE_MAM_TIC";
70"P12V_OCP_V3_2_ISENSE_MPS_TIC"CDS_PHYS_NET_NAME"P12V_OCP_V3_2_ISENSE_MPS_MAM";
71"P3V3_PDB_AUX_ADC_MAM"CDS_PHYS_NET_NAME"P3V3_AUX_SENSE";
72"P3V3_PDB_AUX_ADC_TIC"CDS_PHYS_NET_NAME"P3V3_AUX_SENSE";
73"P1V581_PDB_ADC"CDS_PHYS_NET_NAME"SMB_SEN_3V3AUX_SCL";
74"P12V_AUX_ADC"CDS_PHYS_NET_NAME"P5V_SENSE";
75"P3V3_ADC_MAM"CDS_PHYS_NET_NAME"P3V3_AUX_SENSE";
76"P3V3_AUX_ADC"CDS_PHYS_NET_NAME"P3V3_AUX_SENSE";
77"P3V3_ADC_TIC"CDS_PHYS_NET_NAME"P3V3_AUX_SENSE";
78"P12V_OCP_V3_2_ISENSE_MAM_TIC"CDS_PHYS_NET_NAME"P12V_OCP_V3_2_ISENSE_MAM_TIC";
79"P12V_OCP_SFF_ISENSE_MAM"CDS_PHYS_NET_NAME"P12V_OCP_SFF_ISENSE_MAM";
80"P5V_ADC"CDS_PHYS_NET_NAME"P3V3_AUX_SENSE";
81"P5V_ADC_TIC"CDS_PHYS_NET_NAME"P3V3_AUX_SENSE";
82"P5V_ADC_MAM"CDS_PHYS_NET_NAME"P3V3_AUX_SENSE";
83"P3V3_AUX_ADC_TIC"CDS_PHYS_NET_NAME"P3V3_AUX_SENSE";
84"P3V3_PDB_AUX_ADC_TIC"CDS_PHYS_NET_NAME"P3V3_PDB_AUX_ADC_TIC";
85"SMB_VR_3V3AUX_SCL_R1"CDS_PHYS_NET_NAME"SMB_TEMP_3V3AUX_SCL";
86"ADC128_A1"CDS_PHYS_NET_NAME"SMB_SEN_3V3AUX_SCL";
87"P3V3_PDB_AUX_ADC_MAM"CDS_PHYS_NET_NAME"P3V3_PDB_AUX_ADC_MAM";
88"P3V3_AUX_ADC_MAM"CDS_PHYS_NET_NAME"P3V3_AUX_ADC_MAM";
89"SMB_VR_3V3AUX_SDA_R1"CDS_PHYS_NET_NAME"SMB_TEMP_3V3AUX_SDA";
90"P12V_E1S_0_ISENSE_MAM"CDS_PHYS_NET_NAME"P3V3_PDB_AUX_ADC_MAM";
91"SMB_SEN_MAM_3V3AUX_SCL"CDS_PHYS_NET_NAME"SMB_SEN_3V3AUX_SCL";
92"SMB_SEN_MAM_3V3AUX_SCL"CDS_PHYS_NET_NAME"SMB_TMP75_2_3V3AUX_SCL_R";
93"P12V_OCP_SFF_ISENSE_TIC"CDS_PHYS_NET_NAME"P3V3_AUX_ADC_TIC";
94"P12V_AUX_ADC_TIC"CDS_PHYS_NET_NAME"SMB_SEN_3V3AUX_SCL";
95"P3V3_ADC_MAM"CDS_PHYS_NET_NAME"P3V3_ADC_MAM";
96"P12V_OCP_SFF_ISENSE_MPS_MAM"CDS_PHYS_NET_NAME"P12V_OCP_SFF_ISENSE_MPS_MAM";
97"MAX11617_VREF_R";
98"P3V3_ADC"CDS_PHYS_NET_NAME"P3V3_AUX_SENSE";
99"P12V_OCP_V3_2_ISENSE_TIC"CDS_PHYS_NET_NAME"P3V3_PDB_AUX_ADC_TIC";
100"SMB_SEN_MAM_3V3AUX_SDA"CDS_PHYS_NET_NAME"SMB_TMP75_2_3V3AUX_SCL_R";
101"ADC128_A1"CDS_PHYS_NET_NAME"TCA9539_0_ADD1";
102"ADC128_A0"CDS_PHYS_NET_NAME"TCA9539_0_ADD0";
103"P3V3_MAX11617 _VDD";
104"MAX11617_VREF";
105"SMB_SEN_TIC_3V3AUX_SDA"CDS_PHYS_NET_NAME"SMB_TMP75_21_3V3AUX_SDA_R";
106"SMB_VR_3V3AUX_SDA_R1"CDS_PHYS_NET_NAME"SMB_TEMP_3V3AUX_SDA";
107"SMB_SEN_TIC_3V3AUX_SCL"CDS_PHYS_NET_NAME"SMB_TMP75_2_3V3AUX_SCL_R";
108"P12V_OCP_SFF_ISENSE_MAM_MAM"CDS_PHYS_NET_NAME"P12V_OCP_SFF_ISENSE_MAM_MAM";
109"P3V3_AUX_ADC_TIC"CDS_PHYS_NET_NAME"P3V3_AUX_ADC_TIC";
110"TP_ADC128_INT"CDS_PHYS_NET_NAME"SMB_SEN_3V3AUX_SCL";
111"SMB_SEN_TIC_3V3AUX_SCL"CDS_PHYS_NET_NAME"SMB_TMP75_2_3V3AUX_SCL_R";
%"UNIVERSAL_GND"
"1","(6000,3350)","0","logical_power","I101";
;
HDL_POWER"GND"
CDS_LIB"logical_power";
"A"30;
%"UNIVERSAL_GND"
"1","(4975,3400)","0","logical_power","I102";
;
HDL_POWER"GND"
CDS_LIB"logical_power";
"A"31;
%"ADC128D818CIMTXNOPB"
"1","(6275,1300)","0","pure_quanta","I103";
;
PART_NUMBER"AL000128K00"
PART_TYPE"SMLF"
VALUE"ADC128D818CIMTX/NOPB"
ROOM"ADC1_BOM2"
MATERIAL"IC"
$LOCATION"U269"
CDS_LIB"pure_quanta"
CDS_LMAN_SYM_OUTLINE"-250,475,250,-475"
PIN_NAMES_ROTATE"True"
CDS_LOCATION"U269"
$SEC"1"
CDS_SEC"1";
"INT# \B"
$PN"6"110;
"GND"
$PN"4"25;
"SCL"
$PN"3"107;
"SDA"
$PN"2"42;
"IN0"
$PN"16"94;
"IN1"
$PN"15"93;
"IN2"
$PN"14"99;
"IN3"
$PN"13"59;
"IN4"
$PN"12"60;
"IN5"
$PN"11"109;
"IN6"
$PN"10"84;
"IN7"
$PN"9"61;
"A1"
$PN"8"86;
"A0"
$PN"7"41;
"V+"
$PN"5"40;
"VREF"
$PN"1"58;
%"Q_RES"
"1","(6350,250)","0","pure_quanta","I110";
;
PART_NUMBER"CS00002JB13"
VALUE"0"
TOLERANCE"5%"
MATERIAL"CHIP"
PACK_TYPE"0402LF"
WATTAGE"1/16W"
ROOM"ADC1_BOM2"
$LOCATION"R3671"
CDS_LIB"pure_quanta"
CDS_LOCATION"R3671"
$SEC"1"
CDS_SEC"1";
"B"
$PN"2"105;
"A"
$PN"1"106;
%"Q_RES"
"1","(6350,200)","0","pure_quanta","I111";
;
PART_NUMBER"CS00002JB13"
TOLERANCE"5%"
MATERIAL"CHIP"
VALUE"0"
ROOM"ADC1_BOM2"
$LOCATION"R3672"
WATTAGE"1/16W"
CDS_LIB"pure_quanta"
PACK_TYPE"0402LF"
CDS_LOCATION"R3672"
$SEC"1"
CDS_SEC"1";
"B"
$PN"2"111;
"A"
$PN"1"85;
%"UNIVERSAL_POWER"
"1","(3250,2150)","0","logical_power","I117";
;
HDL_POWER"P3V3_AUX"
CDS_LIB"logical_power";
"A"2;
%"Q_INDUCTOR"
"1","(3550,1925)","0","pure_quanta","I118";
;
PART_NUMBER"TMP_QCX8PG300001"
MATERIAL"IND"
ROOM"ADC1_BOM2"
VALUE"BLM18PG300SN1D "
PACK_TYPE"SMLF"
$LOCATION"L16"
CDS_LIB"pure_quanta"
NEEDS_NO_SIZE"TRUE"
CDS_LOCATION"L16"
$SEC"1"
CDS_SEC"1";
"1"
$PN"1"2;
"2"
$PN"2"40;
%"Q_CAP"
"1","(3725,1700)","2","pure_quanta","I127";
;
PART_NUMBER"CH4104K1B00"
VALUE"0.1UF"
VOLTAGE"25V"
TOLERANCE"10%"
MATERIAL"X7R"
PACK_TYPE"0402"
ROOM"ADC1_BOM2"
$LOCATION"C2051"
CDS_LIB"pure_quanta"
CDS_LOCATION"C2051"
$SEC"1"
CDS_SEC"1";
"B"
$PN"2"24;
"A"
$PN"1"40;
%"Q_CAP"
"1","(4050,1700)","0","pure_quanta","I128";
;
PART_NUMBER"CH4104K1B00"
MATERIAL"X7R"
PACK_TYPE"0402"
TOLERANCE"10%"
ROOM"ADC1_BOM2"
VALUE"0.1UF"
VOLTAGE"25V"
$LOCATION"C2052"
CDS_LIB"pure_quanta"
CDS_LOCATION"C2052"
$SEC"1"
CDS_SEC"1";
"B"
$PN"2"24;
"A"
$PN"1"40;
%"Q_RES"
"2","(4425,1700)","0","pure_quanta","I129";
;
PART_NUMBER"CS24702FB06"
VALUE"4.7K"
TOLERANCE"1%"
PACK_TYPE"0402LF"
MATERIAL"EMPTY"
WATTAGE"1/16W"
$LOCATION"R3689"
CDS_LIB"pure_quanta"
CDS_LOCATION"R3689"
$SEC"1"
CDS_SEC"1";
"A"
$PN"1"40;
"B"
$PN"2"58;
%"UNIVERSAL_GND"
"1","(3725,1375)","0","logical_power","I130";
;
HDL_POWER"GND"
CDS_LIB"logical_power";
"A"24;
%"Q_RES"
"2","(4425,1200)","0","pure_quanta","I131";
;
PART_NUMBER"CS24702FB06"
WATTAGE"1/16W"
VALUE"4.7K"
TOLERANCE"1%"
MATERIAL"EMPTY"
PACK_TYPE"0402LF"
$LOCATION"R3690"
CDS_LIB"pure_quanta"
CDS_LOCATION"R3690"
$SEC"1"
CDS_SEC"1";
"A"
$PN"1"58;
"B"
$PN"2"23;
%"UNIVERSAL_GND"
"1","(4425,875)","0","logical_power","I132";
;
CDS_LIB"logical_power"
HDL_POWER"GND";
"A"23;
%"UNIVERSAL_GND"
"1","(6850,675)","0","logical_power","I133";
;
CDS_LIB"logical_power"
HDL_POWER"GND";
"A"25;
%"UNIVERSAL_POWER"
"1","(-1000,5675)","0","logical_power","I140";
;
HDL_POWER"P3V3_AUX"
CDS_LIB"logical_power";
"A"1;
%"Q_RES"
"2","(-1000,5425)","0","pure_quanta","I141";
;
PART_NUMBER"CS25112FB04"
WATTAGE"1/16W"
TOLERANCE"1%"
PACK_TYPE"0402LF"
MATERIAL"CHIP"
VALUE"5.11K"
$LOCATION"R2907"
CDS_LIB"pure_quanta"
CDS_LOCATION"R2907"
$SEC"1"
CDS_SEC"1";
"A"
$PN"1"1;
"B"
$PN"2"76;
%"Q_RES"
"2","(-1000,4900)","0","pure_quanta","I149";
;
PART_NUMBER"CS24702FB06"
VALUE"4.7K"
WATTAGE"1/16W"
TOLERANCE"1%"
PACK_TYPE"0402LF"
MATERIAL"CHIP"
$LOCATION"R1785"
CDS_LIB"pure_quanta"
CDS_LOCATION"R1785"
$SEC"1"
CDS_SEC"1";
"A"
$PN"1"76;
"B"
$PN"2"22;
%"UNIVERSAL_GND"
"1","(-1000,4550)","0","logical_power","I150";
;
CDS_LIB"logical_power"
HDL_POWER"GND";
"A"22;
%"UNIVERSAL_POWER"
"1","(-1000,4350)","0","logical_power","I160";
;
HDL_POWER"P3V3"
CDS_LIB"logical_power";
"A"7;
%"Q_RES"
"2","(-1000,4100)","0","pure_quanta","I161";
;
PART_NUMBER"CS25112FB04"
TOLERANCE"1%"
WATTAGE"1/16W"
PACK_TYPE"0402LF"
VALUE"5.11K"
MATERIAL"CHIP"
$LOCATION"R2908"
CDS_LIB"pure_quanta"
CDS_LOCATION"R2908"
$SEC"1"
CDS_SEC"1";
"A"
$PN"1"7;
"B"
$PN"2"98;
%"Q_RES"
"2","(-1000,3625)","0","pure_quanta","I162";
;
PART_NUMBER"CS24702FB06"
VALUE"4.7K"
WATTAGE"1/16W"
TOLERANCE"1%"
MATERIAL"CHIP"
PACK_TYPE"0402LF"
$LOCATION"R2843"
CDS_LIB"pure_quanta"
CDS_LOCATION"R2843"
$SEC"1"
CDS_SEC"1";
"A"
$PN"1"98;
"B"
$PN"2"21;
%"Q_RES"
"2","(-1000,2400)","0","pure_quanta","I163";
;
PART_NUMBER"CS29092FB05"
MATERIAL"CHIP"
TOLERANCE"1%"
VALUE"9.09K"
PACK_TYPE"0402LF"
WATTAGE"1/16W"
$LOCATION"R1791"
CDS_LIB"pure_quanta"
CDS_LOCATION"R1791"
$SEC"1"
CDS_SEC"1";
"A"
$PN"1"80;
"B"
$PN"2"20;
%"UNIVERSAL_POWER"
"1","(-1000,3200)","0","logical_power","I167";
;
HDL_POWER"P5V"
CDS_LIB"logical_power";
"A"5;
%"Q_RES"
"2","(-1000,2950)","0","pure_quanta","I168";
;
PART_NUMBER"CS31802FB04"
VALUE"18K"
MATERIAL"CHIP"
PACK_TYPE"0402LF"
TOLERANCE"1%"
WATTAGE"1/16W"
$LOCATION"R3005"
CDS_LIB"pure_quanta"
CDS_LOCATION"R3005"
$SEC"1"
CDS_SEC"1";
"A"
$PN"1"5;
"B"
$PN"2"80;
%"UNIVERSAL_POWER"
"1","(-1025,1900)","0","logical_power","I172";
;
HDL_POWER"P12V_AUX"
CDS_LIB"logical_power";
"A"6;
%"Q_RES"
"2","(-1025,1650)","0","pure_quanta","I173";
;
PART_NUMBER"CS27872FB02"
TOLERANCE"1%"
VALUE"7.87K"
PACK_TYPE"0402LF"
MATERIAL"CHIP"
WATTAGE"1/16W"
$LOCATION"R1799"
CDS_LIB"pure_quanta"
CDS_LOCATION"R1799"
$SEC"1"
CDS_SEC"1";
"A"
$PN"1"6;
"B"
$PN"2"74;
%"Q_RES"
"2","(-1025,1200)","0","pure_quanta","I174";
;
PART_NUMBER"CS21212FB05"
VALUE"1.21K"
TOLERANCE"1%"
WATTAGE"1/16W"
MATERIAL"CHIP"
PACK_TYPE"0402LF"
$LOCATION"R1800"
CDS_LIB"pure_quanta"
CDS_LOCATION"R1800"
$SEC"1"
CDS_SEC"1";
"A"
$PN"1"74;
"B"
$PN"2"19;
%"Q_RES"
"1","(-300,5175)","0","pure_quanta","I176";
;
PART_NUMBER"CS00002JB13"
TOLERANCE"5%"
VALUE"0"
MATERIAL"EMPTY"
ROOM"ADC1_BOM1"
$LOCATION"R3681"
PACK_TYPE"0402LF"
WATTAGE"1/16W"
CDS_LIB"pure_quanta"
CDS_LOCATION"R3681"
$SEC"1"
CDS_SEC"1";
"B"
$PN"2"46;
"A"
$PN"1"76;
%"Q_RES"
"1","(-300,5025)","0","pure_quanta","I179";
;
PART_NUMBER"CS00002JB13"
VALUE"0"
TOLERANCE"5%"
ROOM"ADC1_BOM2"
MATERIAL"CHIP"
$LOCATION"R3682"
PACK_TYPE"0402LF"
WATTAGE"1/16W"
CDS_LIB"pure_quanta"
CDS_LOCATION"R3682"
$SEC"1"
CDS_SEC"1";
"B"
$PN"2"83;
"A"
$PN"1"76;
%"Q_CAP"
"1","(425,4775)","0","pure_quanta","I180";
;
PART_NUMBER"CH11006JB18"
VOLTAGE"50V"
TOLERANCE"5%"
MATERIAL"EMPTY"
PACK_TYPE"0402"
VALUE"100PF"
ROOM"ADC1_BOM1"
$LOCATION"C2042"
CDS_LIB"pure_quanta"
CDS_LOCATION"C2042"
$SEC"1"
CDS_SEC"1";
"B"
$PN"2"34;
"A"
$PN"1"46;
%"Q_CAP"
"1","(75,4775)","2","pure_quanta","I181";
;
PART_NUMBER"CH4104K1B00"
PACK_TYPE"0402"
VOLTAGE"25V"
VALUE"0.1UF"
ROOM"ADC1_BOM2"
TOLERANCE"10%"
MATERIAL"X7R"
$LOCATION"C2047"
CDS_LIB"pure_quanta"
CDS_LOCATION"C2047"
$SEC"1"
CDS_SEC"1";
"B"
$PN"2"35;
"A"
$PN"1"83;
%"UNIVERSAL_GND"
"1","(425,4500)","0","logical_power","I182";
;
CDS_LIB"logical_power"
HDL_POWER"GND";
"A"34;
%"UNIVERSAL_GND"
"1","(75,4500)","0","logical_power","I183";
;
HDL_POWER"GND"
CDS_LIB"logical_power";
"A"35;
%"UNIVERSAL_GND"
"1","(325,2000)","0","logical_power","I186";
;
CDS_LIB"logical_power"
HDL_POWER"GND";
"A"13;
%"Q_CAP"
"1","(325,2275)","0","pure_quanta","I187";
;
PART_NUMBER"CH11006JB18"
VOLTAGE"50V"
TOLERANCE"5%"
VALUE"100PF"
MATERIAL"EMPTY"
PACK_TYPE"0402"
ROOM"ADC1_BOM1"
$LOCATION"C2044"
CDS_LIB"pure_quanta"
CDS_LOCATION"C2044"
$SEC"1"
CDS_SEC"1";
"B"
$PN"2"13;
"A"
$PN"1"82;
%"Q_CAP"
"1","(-25,2275)","2","pure_quanta","I188";
;
PART_NUMBER"CH4104K1B00"
VOLTAGE"25V"
MATERIAL"X7R"
VALUE"0.1UF"
ROOM"ADC1_BOM2"
TOLERANCE"10%"
PACK_TYPE"0402"
$LOCATION"C2049"
CDS_LIB"pure_quanta"
CDS_LOCATION"C2049"
$SEC"1"
CDS_SEC"1";
"B"
$PN"2"14;
"A"
$PN"1"81;
%"UNIVERSAL_GND"
"1","(-25,2000)","0","logical_power","I189";
;
HDL_POWER"GND"
CDS_LIB"logical_power";
"A"14;
%"Q_RES"
"1","(5525,3100)","0","pure_quanta","I19";
;
PART_NUMBER"CS00002JB13"
TOLERANCE"5%"
VALUE"0"
MATERIAL"EMPTY"
ROOM"ADC1_BOM1"
$LOCATION"R1793"
CDS_LIB"pure_quanta"
PACK_TYPE"0402LF"
WATTAGE"1/16W"
CDS_LOCATION"R1793"
$SEC"1"
CDS_SEC"1";
"B"
$PN"2"92;
"A"
$PN"1"64;
%"Q_RES"
"1","(-375,2700)","0","pure_quanta","I190";
;
PART_NUMBER"CS00002JB13"
MATERIAL"EMPTY"
VALUE"0"
TOLERANCE"5%"
ROOM"ADC1_BOM1"
$LOCATION"R3685"
PACK_TYPE"0402LF"
WATTAGE"1/16W"
CDS_LIB"pure_quanta"
CDS_LOCATION"R3685"
$SEC"1"
CDS_SEC"1";
"B"
$PN"2"82;
"A"
$PN"1"80;
%"Q_RES"
"1","(-375,2550)","0","pure_quanta","I191";
;
PART_NUMBER"CS00002JB13"
TOLERANCE"5%"
VALUE"0"
MATERIAL"CHIP"
ROOM"ADC1_BOM2"
$LOCATION"R3686"
PACK_TYPE"0402LF"
WATTAGE"1/16W"
CDS_LIB"pure_quanta"
CDS_LOCATION"R3686"
$SEC"1"
CDS_SEC"1";
"B"
$PN"2"81;
"A"
$PN"1"80;
%"UNIVERSAL_GND"
"1","(-1000,2100)","0","logical_power","I192";
;
HDL_POWER"GND"
CDS_LIB"logical_power";
"A"20;
%"UNIVERSAL_GND"
"1","(350,3150)","0","logical_power","I195";
;
HDL_POWER"GND"
CDS_LIB"logical_power";
"A"32;
%"Q_CAP"
"1","(350,3425)","0","pure_quanta","I196";
;
PART_NUMBER"CH11006JB18"
MATERIAL"EMPTY"
VOLTAGE"50V"
TOLERANCE"5%"
PACK_TYPE"0402"
VALUE"100PF"
ROOM"ADC1_BOM1"
$LOCATION"C2043"
CDS_LIB"pure_quanta"
CDS_LOCATION"C2043"
$SEC"1"
CDS_SEC"1";
"B"
$PN"2"32;
"A"
$PN"1"75;
%"Q_CAP"
"1","(0,3425)","2","pure_quanta","I197";
;
PART_NUMBER"CH4104K1B00"
MATERIAL"X7R"
VALUE"0.1UF"
VOLTAGE"25V"
TOLERANCE"10%"
PACK_TYPE"0402"
ROOM"ADC1_BOM2"
$LOCATION"C2048"
CDS_LIB"pure_quanta"
CDS_LOCATION"C2048"
$SEC"1"
CDS_SEC"1";
"B"
$PN"2"33;
"A"
$PN"1"77;
%"UNIVERSAL_GND"
"1","(0,3150)","0","logical_power","I198";
;
CDS_LIB"logical_power"
HDL_POWER"GND";
"A"33;
%"Q_RES"
"1","(-375,3850)","0","pure_quanta","I199";
;
PART_NUMBER"CS00002JB13"
VALUE"0"
MATERIAL"EMPTY"
TOLERANCE"5%"
ROOM"ADC1_BOM1"
$LOCATION"R3683"
CDS_LIB"pure_quanta"
WATTAGE"1/16W"
PACK_TYPE"0402LF"
CDS_LOCATION"R3683"
$SEC"1"
CDS_SEC"1";
"B"
$PN"2"75;
"A"
$PN"1"98;
%"Q_RES"
"1","(5525,3150)","0","pure_quanta","I20";
;
PART_NUMBER"CS00002JB13"
MATERIAL"EMPTY"
PACK_TYPE"0402LF"
WATTAGE"1/16W"
VALUE"0"
TOLERANCE"5%"
ROOM"ADC1_BOM1"
$LOCATION"R1792"
CDS_LIB"pure_quanta"
CDS_LOCATION"R1792"
$SEC"1"
CDS_SEC"1";
"B"
$PN"2"57;
"A"
$PN"1"89;
%"Q_RES"
"1","(-375,3700)","0","pure_quanta","I200";
;
PART_NUMBER"CS00002JB13"
VALUE"0"
MATERIAL"CHIP"
TOLERANCE"5%"
ROOM"ADC1_BOM2"
$LOCATION"R3684"
CDS_LIB"pure_quanta"
WATTAGE"1/16W"
PACK_TYPE"0402LF"
CDS_LOCATION"R3684"
$SEC"1"
CDS_SEC"1";
"B"
$PN"2"77;
"A"
$PN"1"98;
%"UNIVERSAL_GND"
"1","(-1000,3375)","0","logical_power","I201";
;
HDL_POWER"GND"
CDS_LIB"logical_power";
"A"21;
%"UNIVERSAL_GND"
"1","(-1025,900)","0","logical_power","I202";
;
HDL_POWER"GND"
CDS_LIB"logical_power";
"A"19;
%"Q_CAP"
"1","(700,975)","0","pure_quanta","I205";
;
PART_NUMBER"CH11006JB18"
ROOM"ADC1_BOM1"
VALUE"100PF"
VOLTAGE"50V"
TOLERANCE"5%"
MATERIAL"EMPTY"
PACK_TYPE"0402"
$LOCATION"C1344"
CDS_LIB"pure_quanta"
CDS_LOCATION"C1344"
$SEC"1"
CDS_SEC"1";
"B"
$PN"2"18;
"A"
$PN"1"66;
%"UNIVERSAL_GND"
"1","(700,700)","0","logical_power","I206";
;
HDL_POWER"GND"
CDS_LIB"logical_power";
"A"18;
%"Q_CAP"
"1","(350,975)","2","pure_quanta","I207";
;
PART_NUMBER"CH4104K1B00"
VOLTAGE"25V"
VALUE"0.1UF"
ROOM"ADC1_BOM2"
MATERIAL"X7R"
PACK_TYPE"0402"
TOLERANCE"10%"
$LOCATION"C2046"
CDS_LIB"pure_quanta"
CDS_LOCATION"C2046"
$SEC"1"
CDS_SEC"1";
"B"
$PN"2"17;
"A"
$PN"1"65;
%"UNIVERSAL_GND"
"1","(350,700)","0","logical_power","I208";
;
CDS_LIB"logical_power"
HDL_POWER"GND";
"A"17;
%"Q_RES"
"1","(-200,1400)","0","pure_quanta","I209";
;
PART_NUMBER"CS00002JB13"
ROOM"ADC1_BOM1"
MATERIAL"EMPTY"
TOLERANCE"5%"
VALUE"0"
$LOCATION"R3679"
PACK_TYPE"0402LF"
WATTAGE"1/16W"
CDS_LIB"pure_quanta"
CDS_LOCATION"R3679"
$SEC"1"
CDS_SEC"1";
"B"
$PN"2"66;
"A"
$PN"1"74;
%"Q_RES"
"1","(-200,1250)","0","pure_quanta","I210";
;
PART_NUMBER"CS00002JB13"
TOLERANCE"5%"
MATERIAL"CHIP"
VALUE"0"
ROOM"ADC1_BOM2"
$LOCATION"R3680"
PACK_TYPE"0402LF"
WATTAGE"1/16W"
CDS_LIB"pure_quanta"
CDS_LOCATION"R3680"
$SEC"1"
CDS_SEC"1";
"B"
$PN"2"65;
"A"
$PN"1"74;
%"UNIVERSAL_GND"
"1","(3350,-300)","0","logical_power","I222";
;
HDL_POWER"GND"
CDS_LIB"logical_power";
"A"26;
%"Q_RES"
"2","(3350,-75)","0","pure_quanta","I223";
;
PART_NUMBER"CS21002FB06"
VALUE"1K"
PACK_TYPE"0402LF"
TOLERANCE"1%"
MATERIAL"CHIP"
WATTAGE"1/16W"
ROOM"ADC1_BOM2"
$LOCATION"R3668"
CDS_LIB"pure_quanta"
CDS_LOCATION"R3668"
$SEC"1"
CDS_SEC"1";
"A"
$PN"1"101;
"B"
$PN"2"26;
%"Q_RES"
"2","(3350,525)","0","pure_quanta","I224";
;
PART_NUMBER"CS21002FB06"
TOLERANCE"1%"
WATTAGE"1/16W"
MATERIAL"EMPTY"
PACK_TYPE"0402LF"
VALUE"1K"
$LOCATION"R3667"
CDS_LIB"pure_quanta"
CDS_LOCATION"R3667"
$SEC"1"
CDS_SEC"1";
"A"
$PN"1"3;
"B"
$PN"2"101;
%"UNIVERSAL_POWER"
"1","(3350,925)","0","logical_power","I225";
;
HDL_POWER"P3V3_AUX"
CDS_LIB"logical_power";
"A"3;
%"UNIVERSAL_GND"
"1","(3600,-300)","0","logical_power","I226";
;
HDL_POWER"GND"
CDS_LIB"logical_power";
"A"27;
%"Q_RES"
"2","(3600,-75)","0","pure_quanta","I227";
;
PART_NUMBER"CS21002FB06"
PACK_TYPE"0402LF"
MATERIAL"CHIP"
WATTAGE"1/16W"
TOLERANCE"1%"
VALUE"1K"
ROOM"ADC1_BOM2"
$LOCATION"R3670"
CDS_LIB"pure_quanta"
CDS_LOCATION"R3670"
$SEC"1"
CDS_SEC"1";
"A"
$PN"1"102;
"B"
$PN"2"27;
%"Q_RES"
"2","(3600,525)","0","pure_quanta","I228";
;
PART_NUMBER"CS21002FB06"
VALUE"1K"
TOLERANCE"1%"
WATTAGE"1/16W"
MATERIAL"EMPTY"
PACK_TYPE"0402LF"
$LOCATION"R3669"
CDS_LIB"pure_quanta"
CDS_LOCATION"R3669"
$SEC"1"
CDS_SEC"1";
"A"
$PN"1"3;
"B"
$PN"2"102;
%"Q_CAP"
"1","(1375,75)","0","pure_quanta","I236";
;
PART_NUMBER"CH11006JB18"
TOLERANCE"5%"
VOLTAGE"50V"
MATERIAL"EMPTY"
PACK_TYPE"0402"
VALUE"100PF"
ROOM"ADC1_BOM1"
$LOCATION"C2045"
CDS_LIB"pure_quanta"
CDS_LOCATION"C2045"
$SEC"1"
CDS_SEC"1";
"B"
$PN"2"10;
"A"
$PN"1"71;
%"UNIVERSAL_GND"
"1","(1375,-200)","0","logical_power","I237";
;
CDS_LIB"logical_power"
HDL_POWER"GND";
"A"10;
%"Q_CAP"
"1","(1025,75)","2","pure_quanta","I238";
;
PART_NUMBER"CH4104K1B00"
MATERIAL"X7R"
TOLERANCE"10%"
PACK_TYPE"0402"
VOLTAGE"25V"
VALUE"0.1UF"
ROOM"ADC1_BOM2"
$LOCATION"C2050"
CDS_LIB"pure_quanta"
CDS_LOCATION"C2050"
$SEC"1"
CDS_SEC"1";
"B"
$PN"2"9;
"A"
$PN"1"72;
%"UNIVERSAL_GND"
"1","(1025,-175)","0","logical_power","I239";
;
HDL_POWER"GND"
CDS_LIB"logical_power";
"A"9;
%"Q_RES"
"1","(475,500)","0","pure_quanta","I240";
;
PART_NUMBER"CS00002JB13"
VALUE"0"
TOLERANCE"5%"
ROOM"ADC1_BOM1"
MATERIAL"EMPTY"
$LOCATION"R3687"
CDS_LIB"pure_quanta"
WATTAGE"1/16W"
PACK_TYPE"0402LF"
CDS_LOCATION"R3687"
$SEC"1"
CDS_SEC"1";
"B"
$PN"2"71;
"A"
$PN"1"73;
%"Q_RES"
"1","(475,350)","0","pure_quanta","I241";
;
PART_NUMBER"CS00002JB13"
MATERIAL"CHIP"
TOLERANCE"5%"
VALUE"0"
ROOM"ADC1_BOM2"
$LOCATION"R3688"
CDS_LIB"pure_quanta"
WATTAGE"1/16W"
PACK_TYPE"0402LF"
CDS_LOCATION"R3688"
$SEC"1"
CDS_SEC"1";
"B"
$PN"2"72;
"A"
$PN"1"73;
%"UNIVERSAL_GND"
"1","(2975,4850)","0","logical_power","I303";
;
CDS_LIB"logical_power"
HDL_POWER"GND";
"A"39;
%"Q_CAP"
"1","(2975,5050)","0","pure_quanta","I304";
;
PART_NUMBER"CH11006JB18"
VALUE"100PF"
MATERIAL"EMPTY"
VOLTAGE"50V"
PACK_TYPE"0402"
ROOM"ADC1_BOM1"
TOLERANCE"5%"
$LOCATION"C2176"
CDS_LIB"pure_quanta"
CDS_LOCATION"C2176"
$SEC"1"
CDS_SEC"1";
"B"
$PN"2"39;
"A"
$PN"1"79;
%"Q_CAP"
"1","(2950,4525)","2","pure_quanta","I305";
;
PART_NUMBER"CH4104K1B00"
VOLTAGE"25V"
VALUE"0.1UF"
MATERIAL"X7R"
TOLERANCE"10%"
ROOM"ADC1_BOM2"
PACK_TYPE"0402"
$LOCATION"C2178"
CDS_LIB"pure_quanta"
CDS_LOCATION"C2178"
$SEC"1"
CDS_SEC"1";
"B"
$PN"2"38;
"A"
$PN"1"48;
%"UNIVERSAL_GND"
"1","(2950,4350)","0","logical_power","I306";
;
HDL_POWER"GND"
CDS_LIB"logical_power";
"A"38;
%"Q_CAP"
"1","(2950,4075)","0","pure_quanta","I309";
;
PART_NUMBER"CH11006JB18"
VOLTAGE"50V"
TOLERANCE"5%"
VALUE"100PF"
MATERIAL"EMPTY"
ROOM"ADC1_BOM1"
PACK_TYPE"0402"
$LOCATION"C2175"
CDS_LIB"pure_quanta"
CDS_LOCATION"C2175"
$SEC"1"
CDS_SEC"1";
"B"
$PN"2"15;
"A"
$PN"1"49;
%"UNIVERSAL_GND"
"1","(2950,3875)","0","logical_power","I310";
;
HDL_POWER"GND"
CDS_LIB"logical_power";
"A"15;
%"Q_CAP"
"1","(2925,3550)","2","pure_quanta","I311";
;
PART_NUMBER"CH4104K1B00"
VOLTAGE"25V"
PACK_TYPE"0402"
MATERIAL"X7R"
TOLERANCE"10%"
VALUE"0.1UF"
ROOM"ADC1_BOM2"
$LOCATION"C2177"
CDS_LIB"pure_quanta"
CDS_LOCATION"C2177"
$SEC"1"
CDS_SEC"1";
"B"
$PN"2"16;
"A"
$PN"1"50;
%"UNIVERSAL_GND"
"1","(2925,3375)","0","logical_power","I312";
;
CDS_LIB"logical_power"
HDL_POWER"GND";
"A"16;
%"Q_RES"
"1","(2250,5200)","0","pure_quanta","I313";
;
PART_NUMBER"CS00002JB13"
MATERIAL"EMPTY"
VALUE"0"
TOLERANCE"5%"
ROOM"NIC1_P12V_MAM_MAM_BOM1"
$LOCATION"R3863"
PACK_TYPE"0402LF"
WATTAGE"1/16W"
CDS_LIB"pure_quanta"
CDS_LOCATION"R3863"
$SEC"1"
CDS_SEC"1";
"B"
$PN"2"79;
"A"
$PN"1"108;
%"Q_RES"
"1","(2250,5050)","0","pure_quanta","I314";
;
PART_NUMBER"CS00002JB13"
TOLERANCE"5%"
VALUE"0"
MATERIAL"EMPTY"
ROOM"NIC1_P12V_MPS_MAM_BOM3"
$LOCATION"R3864"
CDS_LIB"pure_quanta"
WATTAGE"1/16W"
PACK_TYPE"0402LF"
CDS_LOCATION"R3864"
$SEC"1"
CDS_SEC"1";
"B"
$PN"2"79;
"A"
$PN"1"96;
%"Q_RES"
"1","(2250,4700)","0","pure_quanta","I315";
;
PART_NUMBER"CS00002JB13"
TOLERANCE"5%"
VALUE"0"
MATERIAL"EMPTY"
ROOM1"NIC1_P12V_MAM_TIC_BOM2"
$LOCATION"R3865"
PACK_TYPE"0402LF"
WATTAGE"1/16W"
CDS_LIB"pure_quanta"
CDS_LOCATION"R3865"
$SEC"1"
CDS_SEC"1";
"B"
$PN"2"48;
"A"
$PN"1"45;
%"Q_RES"
"1","(2250,4550)","0","pure_quanta","I316";
;
PART_NUMBER"CS00002JB13"
VALUE"0"
TOLERANCE"5%"
MATERIAL"CHIP"
ROOM1"NIC1_P12V_MPS_TIC_BOM4"
$LOCATION"R3866"
PACK_TYPE"0402LF"
WATTAGE"1/16W"
CDS_LIB"pure_quanta"
CDS_LOCATION"R3866"
$SEC"1"
CDS_SEC"1";
"B"
$PN"2"48;
"A"
$PN"1"44;
%"Q_RES"
"1","(2225,4225)","0","pure_quanta","I321";
;
PART_NUMBER"CS00002JB13"
VALUE"0"
MATERIAL"EMPTY"
TOLERANCE"5%"
ROOM"NIC1_P12V_MAM_MAM_BOM1 "
$LOCATION"R3859"
CDS_LIB"pure_quanta"
WATTAGE"1/16W"
PACK_TYPE"0402LF"
CDS_LOCATION"R3859"
$SEC"1"
CDS_SEC"1";
"B"
$PN"2"49;
"A"
$PN"1"47;
%"Q_RES"
"1","(2225,4075)","0","pure_quanta","I322";
;
PART_NUMBER"CS00002JB13"
VALUE"0"
TOLERANCE"5%"
ROOM"NIC1_P12V_MPS_MAM_BOM3 "
MATERIAL"EMPTY"
$LOCATION"R3860"
PACK_TYPE"0402LF"
WATTAGE"1/16W"
CDS_LIB"pure_quanta"
CDS_LOCATION"R3860"
$SEC"1"
CDS_SEC"1";
"B"
$PN"2"49;
"A"
$PN"1"53;
%"Q_RES"
"1","(2225,3725)","0","pure_quanta","I323";
;
PART_NUMBER"CS00002JB13"
VALUE"0"
MATERIAL"EMPTY"
TOLERANCE"5%"
ROOM1"NIC1_P12V_MAM_TIC_BOM2 "
$LOCATION"R3861"
CDS_LIB"pure_quanta"
WATTAGE"1/16W"
PACK_TYPE"0402LF"
CDS_LOCATION"R3861"
$SEC"1"
CDS_SEC"1";
"B"
$PN"2"50;
"A"
$PN"1"78;
%"Q_RES"
"1","(2225,3575)","0","pure_quanta","I324";
;
PART_NUMBER"CS00002JB13"
TOLERANCE"5%"
MATERIAL"CHIP"
VALUE"0"
ROOM1"NIC1_P12V_MPS_TIC_BOM4 "
$LOCATION"R3862"
CDS_LIB"pure_quanta"
WATTAGE"1/16W"
PACK_TYPE"0402LF"
CDS_LOCATION"R3862"
$SEC"1"
CDS_SEC"1";
"B"
$PN"2"50;
"A"
$PN"1"70;
%"Q_RES"
"1","(2200,3225)","0","pure_quanta","I330";
;
PART_NUMBER"CS00002JB13"
VALUE"0"
TOLERANCE"5%"
MATERIAL"EMPTY"
ROOM"E1S1_P12V_MAM_MAM_BOM1"
$LOCATION"R3939"
CDS_LIB"pure_quanta"
WATTAGE"1/16W"
PACK_TYPE"0402LF"
CDS_LOCATION"R3939"
$SEC"1"
CDS_SEC"1";
"B"
$PN"2"51;
"A"
$PN"1"55;
%"Q_CAP"
"1","(2925,3075)","0","pure_quanta","I333";
;
PART_NUMBER"CH11006JB18"
PACK_TYPE"0402"
TOLERANCE"5%"
VOLTAGE"50V"
MATERIAL"EMPTY"
ROOM"ADC1_BOM1"
VALUE"100PF"
$LOCATION"C2195"
CDS_LIB"pure_quanta"
CDS_LOCATION"C2195"
$SEC"1"
CDS_SEC"1";
"B"
$PN"2"12;
"A"
$PN"1"51;
%"UNIVERSAL_GND"
"1","(2925,2875)","0","logical_power","I334";
;
CDS_LIB"logical_power"
HDL_POWER"GND";
"A"12;
%"UNIVERSAL_GND"
"1","(2900,2375)","0","logical_power","I335";
;
CDS_LIB"logical_power"
HDL_POWER"GND";
"A"11;
%"Q_CAP"
"1","(2900,2550)","2","pure_quanta","I336";
;
PART_NUMBER"CH4104K1B00"
VALUE"0.1UF"
ROOM"ADC1_BOM2"
TOLERANCE"10%"
MATERIAL"X7R"
VOLTAGE"25V"
PACK_TYPE"0402"
$LOCATION"C2194"
CDS_LIB"pure_quanta"
CDS_LOCATION"C2194"
$SEC"1"
CDS_SEC"1";
"B"
$PN"2"11;
"A"
$PN"1"67;
%"Q_RES"
"1","(2200,3075)","0","pure_quanta","I337";
;
PART_NUMBER"CS00002JB13"
VALUE"0"
TOLERANCE"5%"
MATERIAL"EMPTY"
ROOM"E1S1_P12V_MPS_MAM_BOM3"
$LOCATION"R3940"
PACK_TYPE"0402LF"
WATTAGE"1/16W"
CDS_LIB"pure_quanta"
CDS_LOCATION"R3940"
$SEC"1"
CDS_SEC"1";
"B"
$PN"2"51;
"A"
$PN"1"52;
%"Q_RES"
"1","(2200,2725)","0","pure_quanta","I338";
;
PART_NUMBER"CS00002JB13"
VALUE"0"
TOLERANCE"5%"
MATERIAL"EMPTY"
ROOM1"E1S1_P12V_MAM_TIC_BOM2"
$LOCATION"R3941"
PACK_TYPE"0402LF"
WATTAGE"1/16W"
CDS_LIB"pure_quanta"
CDS_LOCATION"R3941"
$SEC"1"
CDS_SEC"1";
"B"
$PN"2"67;
"A"
$PN"1"69;
%"Q_RES"
"1","(2200,2575)","0","pure_quanta","I339";
;
PART_NUMBER"CS00002JB13"
VALUE"0"
MATERIAL"CHIP"
ROOM1"E1S1_P12V_MPS_TIC_BOM4"
TOLERANCE"5%"
$LOCATION"R3942"
PACK_TYPE"0402LF"
WATTAGE"1/16W"
CDS_LIB"pure_quanta"
CDS_LOCATION"R3942"
$SEC"1"
CDS_SEC"1";
"B"
$PN"2"67;
"A"
$PN"1"68;
%"Q_RES"
"2","(-475,150)","0","pure_quanta","I346";
;
PART_NUMBER"CS24702FB06"
PACK_TYPE"0402LF"
TOLERANCE"1%"
VALUE"4.7K"
WATTAGE"1/16W"
MATERIAL"CHIP"
$LOCATION"R4568"
CDS_LIB"pure_quanta"
CDS_LOCATION"R4568"
$SEC"1"
CDS_SEC"1";
"A"
$PN"1"73;
"B"
$PN"2"8;
%"UNIVERSAL_GND"
"1","(-475,-75)","0","logical_power","I347";
;
CDS_LIB"logical_power"
HDL_POWER"GND";
"A"8;
%"Q_RES"
"2","(-475,525)","0","pure_quanta","I348";
;
PART_NUMBER"CS25112FB04"
WATTAGE"1/16W"
TOLERANCE"1%"
MATERIAL"CHIP"
PACK_TYPE"0402LF"
VALUE"5.11K"
$LOCATION"R4567"
CDS_LIB"pure_quanta"
CDS_LOCATION"R4567"
$SEC"1"
CDS_SEC"1";
"A"
$PN"1"43;
"B"
$PN"2"73;
%"MAX11617EEET"
"1","(5475,4100)","0","pure_quanta","I57";
;
PART_NUMBER"AL011617W00"
ROOM"ADC1_BOM1"
VALUE"MAX11617EEE+T"
PART_TYPE"SMLF"
MATERIAL"EMPTY"
$LOCATION"U193"
CDS_LIB"pure_quanta"
NEEDS_NO_SIZE"TRUE"
CDS_LMAN_SYM_OUTLINE"-250,400,250,-400"
SEC_TYPE""
CDS_LOCATION"U193"
SEC"1";
"VDD"
$PN"16"103;
"GND"
$PN"15"30;
"SDA"
$PN"14"100;
"SCL"
$PN"13"91;
"AIN7"
$PN"12"90;
"AIN6"
$PN"11"87;
"AIN5"
$PN"10"88;
"AIN4"
$PN"9"95;
"AIN3"
$PN"8"63;
"AIN2"
$PN"7"62;
"AIN1"
$PN"6"56;
"AIN0"
$PN"5"54;
"AIN8"
$PN"4"31;
"AIN9"
$PN"3"31;
"AIN10"
$PN"2"31;
"AIN11||REF"
$PN"1"97;
%"Q_CAP"
"1","(6400,4525)","2","pure_quanta","I58";
;
PART_NUMBER"CH4104K1B00"
VALUE"0.1UF"
VOLTAGE"25V"
TOLERANCE"10%"
MATERIAL"EMPTY"
PACK_TYPE"0402"
ROOM"ADC1_BOM1"
$LOCATION"C1757"
CDS_LIB"pure_quanta"
CDS_LOCATION"C1757"
$SEC"1"
CDS_SEC"1";
"B"
$PN"2"29;
"A"
$PN"1"103;
%"UNIVERSAL_GND"
"1","(6400,4350)","0","logical_power","I60";
;
CDS_LIB"logical_power"
HDL_POWER"GND";
"A"29;
%"Q_CAP"
"1","(6775,4525)","0","pure_quanta","I61";
;
PART_NUMBER"CH6103KEA00"
PACK_TYPE"C0805"
VALUE"10UF"
VOLTAGE"16V"
TOLERANCE"10%"
MATERIAL"EMPTY"
ROOM"ADC1_BOM1"
$LOCATION"C1768"
CDS_LIB"pure_quanta"
CDS_LOCATION"C1768"
$SEC"1"
CDS_SEC"1";
"B"
$PN"2"28;
"A"
$PN"1"103;
%"Q_INDUCTOR"
"1","(7100,4750)","0","pure_quanta","I62";
;
PART_NUMBER"TMP_QCX8PG300001"
PACK_TYPE"SMLF"
MATERIAL"EMPTY"
VALUE"BLM18PG300SN1D "
ROOM"ADC1_BOM1"
$LOCATION"L15"
NEEDS_NO_SIZE"TRUE"
CDS_LIB"pure_quanta"
CDS_LOCATION"L15"
$SEC"1"
CDS_SEC"1";
"1"
$PN"1"103;
"2"
$PN"2"4;
%"UNIVERSAL_POWER"
"1","(7525,4950)","0","logical_power","I63";
;
HDL_POWER"P3V3_AUX"
CDS_LIB"logical_power";
"A"4;
%"UNIVERSAL_GND"
"1","(6775,4350)","0","logical_power","I64";
;
CDS_LIB"logical_power"
HDL_POWER"GND";
"A"28;
%"Q_CAP"
"1","(4075,4550)","0","pure_quanta","I68";
;
PART_NUMBER"CH6103KEA00"
MATERIAL"EMPTY"
VOLTAGE"16V"
ROOM"ADC1_BOM1"
PACK_TYPE"C0805"
TOLERANCE"10%"
VALUE"10UF"
$LOCATION"C1767"
CDS_LIB"pure_quanta"
CDS_LOCATION"C1767"
$SEC"1"
CDS_SEC"1";
"B"
$PN"2"36;
"A"
$PN"1"104;
%"UNIVERSAL_GND"
"1","(4075,4350)","0","logical_power","I69";
;
CDS_LIB"logical_power"
HDL_POWER"GND";
"A"36;
%"Q_CAP"
"1","(3700,4550)","2","pure_quanta","I70";
;
PART_NUMBER"CH4104K1B00"
VALUE"0.1UF"
PACK_TYPE"0402"
TOLERANCE"10%"
VOLTAGE"25V"
MATERIAL"EMPTY"
ROOM"ADC1_BOM1"
$LOCATION"C1347"
CDS_LIB"pure_quanta"
CDS_LOCATION"C1347"
$SEC"1"
CDS_SEC"1";
"B"
$PN"2"37;
"A"
$PN"1"104;
%"UNIVERSAL_GND"
"1","(3700,4350)","0","logical_power","I71";
;
HDL_POWER"GND"
CDS_LIB"logical_power";
"A"37;
%"Q_RES"
"1","(4425,4725)","0","pure_quanta","I72";
;
PART_NUMBER"CS22002FB07"
MATERIAL"EMPTY"
VALUE"2K"
PACK_TYPE"0402LF"
ROOM"ADC1_BOM1"
TOLERANCE"1%"
WATTAGE"1/16W"
$LOCATION"R2900"
CDS_LIB"pure_quanta"
CDS_LOCATION"R2900"
$SEC"1"
CDS_SEC"1";
"B"
$PN"2"97;
"A"
$PN"1"104;
END.
